#ISCELL
  mstr_misc dns *
  *
#ISCELL
  mstr_symbols cad_note *
  *
#ISCELL
  mstr_symbols design_note *
  *
#ISCELL
  mstr_symbols intel_corp_bpage *
  *
#ISCELL
  mstr_standard offpage *
  page139_i101
#ISCELL
  mstr_standard offpage *
  page139_i102
#ISCELL
  mstr_standard offpage *
  page139_i103
#ISCELL
  mstr_standard offpage *
  page139_i104
#ISCELL
  mstr_standard offpage *
  page139_i105
#ISCELL
  mstr_standard offpage *
  page139_i106
#ISCELL
  mstr_standard offpage *
  page139_i107
#ISCELL
  mstr_standard offpage *
  page139_i108
#CELL
  mstr_discrete crystal *
  page139_i109
#CELL
  mstr_discrete res *
  page139_i110
#ISCELL
  mstr_symbols gnd *
  page139_i113
#ISCELL
  mstr_symbols gnd *
  page139_i114
#ISCELL
  mstr_standard offpage *
  page139_i115
#ISCELL
  mstr_standard offpage *
  page139_i116
#ISCELL
  mstr_standard offpage *
  page139_i117
#ISCELL
  mstr_standard offpage *
  page139_i118
#ISCELL
  mstr_standard offpage *
  page139_i127
#CELL
  mstr_discrete res *
  page139_i128
#CELL
  mstr_discrete res *
  page139_i129
#CELL
  mstr_discrete res *
  page139_i130
#ISCELL
  mstr_standard offpage *
  page139_i131
#ISCELL
  mstr_standard offpage *
  page139_i132
#ISCELL
  mstr_standard offpage *
  page139_i133
#CELL
  mstr_discrete cap *
  page139_i134
#CELL
  mstr_discrete cap *
  page139_i135
#CELL
  mstr_discrete cap *
  page139_i136
#ISCELL
  mstr_symbols gnd *
  page139_i137
#ISCELL
  mstr_symbols gnd *
  page139_i138
#ISCELL
  mstr_symbols gnd *
  page139_i139
#CELL
  mstr_discrete cap *
  page139_i142
#CELL
  dev_discrete cap_a *
  page139_i143
#CELL
  dev_discrete cap_a *
  page139_i144
#CELL
  dev_discrete cap_a *
  page139_i145
#CELL
  dev_discrete cap_a *
  page139_i146
#CELL
  dev_discrete cap_a *
  page139_i149
#CELL
  dev_discrete cap_a *
  page139_i150
#CELL
  dev_discrete cap_a *
  page139_i151
#CELL
  dev_discrete cap_a *
  page139_i152
#CELL
  mstr_discrete cap *
  page139_i153
#ISCELL
  mstr_symbols p1v5_lan *
  page139_i154
#CELL
  dev_discrete cap_a *
  page139_i157
#CELL
  dev_discrete cap_a *
  page139_i158
#CELL
  dev_discrete cap_a *
  page139_i159
#CELL
  dev_discrete cap_a *
  page139_i160
#CELL
  mstr_discrete cap *
  page139_i161
#ISCELL
  mstr_symbols p0v9_lan *
  page139_i162
#CELL
  dev_discrete cap_a *
  page139_i163
#ISCELL
  mstr_symbols gnd *
  page139_i164
#ISCELL
  mstr_standard offpage *
  page139_i166
#ISCELL
  mstr_standard offpage *
  page139_i167
#ISCELL
  mstr_standard offpage *
  page139_i172
#CELL
  mstr_discrete res *
  page139_i173
#CELL
  mstr_discrete res *
  page139_i174
#ISCELL
  mstr_standard offpage *
  page139_i175
#ISCELL
  mstr_symbols gnd *
  page139_i176
#CELL
  mstr_discrete res *
  page139_i177
#CELL
  mstr_discrete res *
  page139_i178
#CELL
  mstr_discrete res *
  page139_i179
#ISCELL
  mstr_symbols p3v3_stby *
  page139_i180
#CELL
  mstr_discrete res *
  page139_i181
#ISCELL
  mstr_symbols p3v3_stby *
  page139_i182
#ISCELL
  mstr_standard offpage *
  page139_i183
#ISCELL
  mstr_standard offpage *
  page139_i184
#ISCELL
  mstr_standard offpage *
  page139_i185
#ISCELL
  mstr_symbols p3v3_stby *
  page139_i186
#ISCELL
  mstr_symbols p3v3_stby *
  page139_i188
#ISCELL
  mstr_symbols p3v3_stby *
  page139_i189
#ISCELL
  mstr_standard offpage *
  page139_i191
#ISCELL
  mstr_standard offpage *
  page139_i192
#CELL
  mstr_discrete res *
  page139_i193
#ISCELL
  mstr_symbols p3v3_stby *
  page139_i194
#CELL
  mstr_discrete res *
  page139_i195
#ISCELL
  mstr_standard offpage *
  page139_i197
#ISCELL
  mstr_standard offpage *
  page139_i198
#ISCELL
  mstr_symbols p3v3_stby *
  page139_i199
#CELL
  mstr_discrete res *
  page139_i200
#CELL
  mstr_discrete res *
  page139_i201
#ISCELL
  mstr_standard offpage *
  page139_i202
#ISCELL
  mstr_standard offpage *
  page139_i203
#ISCELL
  mstr_symbols gnd *
  page139_i204
#ISCELL
  mstr_standard offpage *
  page139_i206
#ISCELL
  mstr_symbols gnd *
  page139_i207
#ISCELL
  mstr_standard offpage *
  page139_i209
#ISCELL
  mstr_symbols gnd *
  page139_i211
#CELL
  mstr_discrete res *
  page139_i212
#CELL
  mstr_discrete res *
  page139_i213
#CELL
  mstr_discrete res *
  page139_i214
#ISCELL
  mstr_standard offpage *
  page139_i218
#ISCELL
  mstr_standard offpage *
  page139_i219
#ISCELL
  mstr_standard offpage *
  page139_i220
#ISCELL
  mstr_standard offpage *
  page139_i223
#ISCELL
  mstr_standard offpage *
  page139_i224
#CELL
  mstr_discrete res *
  page139_i225
#ISCELL
  mstr_standard offpage *
  page139_i226
#ISCELL
  mstr_standard offpage *
  page139_i227
#CELL
  mstr_discrete res *
  page139_i228
#CELL
  mstr_discrete res *
  page139_i229
#ISCELL
  mstr_standard offpage *
  page139_i230
#ISCELL
  mstr_standard offpage *
  page139_i231
#ISCELL
  mstr_standard offpage *
  page139_i233
#CELL
  mstr_discrete res *
  page139_i235
#ISCELL
  mstr_standard offpage *
  page139_i236
#CELL
  mstr_discrete res *
  page139_i237
#CELL
  mstr_discrete res *
  page139_i238
#CELL
  mstr_discrete res *
  page139_i239
#CELL
  mstr_discrete res *
  page139_i240
#CELL
  dev_discrete cap_a *
  page139_i241
#ISCELL
  mstr_symbols gnd *
  page139_i243
#CELL
  w_hdl sc22u16v5mx-4-gp *
  page139_i244
#CELL
  w_hdl sc22u16v5mx-4-gp *
  page139_i245
#CELL
  w_hdl sc22u16v5mx-4-gp *
  page139_i246
#ISCELL
  mstr_symbols gnd *
  page139_i247
#CELL
  w_hdl sc22u16v5mx-4-gp *
  page139_i248
#CELL
  mstr_discrete cap *
  page139_i249
#CELL
  mstr_discrete cap *
  page139_i250
#ISCELL
  mstr_standard offpage *
  page139_i251
#CELL
  mstr_discrete res *
  page139_i252
#CELL
  mstr_intel springville *
  page139_i72
#ISCELL
  mstr_symbols p0v9_lan *
  page139_i73
#ISCELL
  mstr_symbols p1v5_lan *
  page139_i74
#CELL
  mstr_discrete cap *
  page139_i76
#ISCELL
  mstr_symbols gnd *
  page139_i77
#ISCELL
  mstr_standard offpage *
  page139_i84
#ISCELL
  mstr_standard offpage *
  page139_i85
#ISCELL
  mstr_standard offpage *
  page139_i86
#CELL
  dev_discrete cap_a *
  page139_i87
#CELL
  dev_discrete cap_a *
  page139_i88
#CELL
  dev_discrete cap_a *
  page139_i89
#CELL
  dev_discrete cap_a *
  page139_i90
#ISCELL
  mstr_standard offpage *
  page139_i91
#ISCELL
  mstr_standard offpage *
  page139_i92
#ISCELL
  mstr_standard offpage *
  page139_i93
#ISCELL
  mstr_standard offpage *
  page139_i94
